# BASEBOARD_FAB2 (Tioga Pass) — schematic netlist excerpt (pin names and nets, part order shuffled) for the footprints in the layout excerpt that follows; sources: Cadence DE-HDL packaged netlist, KiCad conversion of Wiwynn_Tioga_Pass_MB.brd

R8B17  RES  4.75K 1% CHIP  pkg 0402  page 91 : A = PVPP_ABC ; B = IRQ_HFI1_CPU0_LVT2_N
C1L16  CAP_A  0.1UF 16V 10% X7R  pkg 0402V  page 196 : A = P3V3 ; B = GND
C1E19  CAP  47.0PF 50V 5% EMPTY  pkg 0402LF  page 167 : A = ISENSE_TMP421_2_DXP ; B = ISENSE_TMP421_2_DXN

(kicad_pcb
	(version 20260206)
	(generator "pcbnew")
	(generator_version "10.0")
	(general
		(thickness 1.6)
		(legacy_teardrops no)
	)
	(paper "A4")
	(title_block
		(title "Wiwynn_Tioga_Pass_MB.brd")
		(comment 1 "Tioga Pass / footprints 2261-2263 of 4770")
	)
	(layers
		(0 "F.Cu" signal "TOP")
		(4 "In1.Cu" signal "L2GND")
		(6 "In2.Cu" signal "L3")
		(8 "In3.Cu" signal "L4GND")
		(10 "In4.Cu" signal "L5")
		(12 "In5.Cu" signal "L6GND")
		(14 "In6.Cu" signal "L7VCC")
		(16 "In7.Cu" signal "L8VCC")
		(18 "In8.Cu" signal "L9GND")
		(20 "In9.Cu" signal "L10")
		(22 "In10.Cu" signal "L11GND")
		(24 "In11.Cu" signal "L12")
		(26 "In12.Cu" signal "L13GND")
		(2 "B.Cu" signal "BOTTOM")
		(9 "F.Adhes" user "F.Adhesive")
		(11 "B.Adhes" user "B.Adhesive")
		(13 "F.Paste" user "Package Geometry/Pastemask Top")
		(15 "B.Paste" user "Package Geometry/Pastemask Bottom")
		(5 "F.SilkS" user "Ref Des/Silkscreen Top")
		(7 "B.SilkS" user "Ref Des/Silkscreen Bottom")
		(1 "F.Mask" user "Board Geometry/Soldermask Top")
		(3 "B.Mask" user "Board Geometry/Soldermask Bottom")
		(17 "Dwgs.User" user "User.Drawings")
		(19 "Cmts.User" user "User.Comments")
		(21 "Eco1.User" user "User.Eco1")
		(23 "Eco2.User" user "User.Eco2")
		(25 "Edge.Cuts" user "Board Geometry/Outline")
		(27 "Margin" user)
		(31 "F.CrtYd" user "Package Geometry/Place Bound Top")
		(29 "B.CrtYd" user "Package Geometry/Place Bound Bottom")
		(35 "F.Fab" user "Ref Des/Assembly Top")
		(33 "B.Fab" user "Ref Des/Assembly Bottom")
	)
	(footprint ""
		(layer "F.Cu")
		(at 0.315468 -68.586858 90)
		(property "Reference" "C1E19"
			(at 0 0 90)
			(layer "F.SilkS")
			(hide yes)
			(effects
				(font
					(size 1.27 1.27)
				)
			)
		)
		(property "Value" ""
			(at 0 0 90)
			(layer "F.Fab")
			(effects
				(font
					(size 1.27 1.27)
				)
			)
		)
		(duplicate_pad_numbers_are_jumpers no)
		(fp_poly
			(pts
				(xy 0.3048 -0.1016) (xy 0.3048 0.9906) (xy -0.3048 0.9906) (xy -0.3048 -0.1016)
			)
			(stroke
				(width 0)
				(type default)
			)
			(fill no)
			(layer "F.CrtYd")
		)
		(fp_line
			(start 0.3048 -0.1016)
			(end -0.3048 -0.1016)
			(stroke
				(width 0.1)
				(type default)
			)
			(layer "F.Fab")
		)
		(fp_line
			(start -0.3048 -0.1016)
			(end -0.3048 0.9906)
			(stroke
				(width 0.1)
				(type default)
			)
			(layer "F.Fab")
		)
		(fp_line
			(start 0.3048 0.9906)
			(end 0.3048 -0.1016)
			(stroke
				(width 0.1)
				(type default)
			)
			(layer "F.Fab")
		)
		(fp_line
			(start -0.3048 0.9906)
			(end 0.3048 0.9906)
			(stroke
				(width 0.1)
				(type default)
			)
			(layer "F.Fab")
		)
		(pad "1" smd rect
			(at 0 0 90)
			(size 0.508 0.508)
			(layers "F.Cu" "F.Mask" "F.Paste")
			(net "ISENSE_TMP421_2_DXP")
		)
		(pad "2" smd rect
			(at 0 0.889 90)
			(size 0.508 0.508)
			(layers "F.Cu" "F.Mask" "F.Paste")
			(net "ISENSE_TMP421_2_DXN")
		)
		(zone
			(layer "F.Cu")
			(hatch none 0.5)
			(connect_pads
				(clearance 0)
			)
			(min_thickness 0.25)
			(keepout
				(tracks allowed)
				(vias not_allowed)
				(pads allowed)
				(copperpour not_allowed)
				(footprints allowed)
			)
			(placement
				(enabled no)
				(sheetname "")
			)
			(fill
				(thermal_gap 0.5)
				(thermal_bridge_width 0.5)
				(island_removal_mode 0)
			)
			(polygon
				(pts
					(xy 0.569468 -68.332858) (xy 0.569468 -68.840858) (xy 0.950468 -68.840858) (xy 0.950468 -68.332858)
				)
			)
		)
		(zone
			(layer "F.Cu")
			(hatch none 0.5)
			(connect_pads
				(clearance 0)
			)
			(min_thickness 0.25)
			(keepout
				(tracks not_allowed)
				(vias allowed)
				(pads allowed)
				(copperpour not_allowed)
				(footprints allowed)
			)
			(placement
				(enabled no)
				(sheetname "")
			)
			(fill
				(thermal_gap 0.5)
				(thermal_bridge_width 0.5)
				(island_removal_mode 0)
			)
			(polygon
				(pts
					(xy 0.950468 -68.332858) (xy 0.950468 -68.840858) (xy 0.569468 -68.840858) (xy 0.569468 -68.332858)
				)
			)
		)
	)
	(footprint ""
		(layer "F.Cu")
		(at 473.827094 -141.608048 -90)
		(property "Reference" "C1L16"
			(at 0 0 270)
			(layer "F.SilkS")
			(hide yes)
			(effects
				(font
					(size 1.27 1.27)
				)
			)
		)
		(property "Value" ""
			(at 0 0 270)
			(layer "F.Fab")
			(effects
				(font
					(size 1.27 1.27)
				)
			)
		)
		(duplicate_pad_numbers_are_jumpers no)
		(fp_poly
			(pts
				(xy 0.3048 -0.1016) (xy 0.3048 0.9906) (xy -0.3048 0.9906) (xy -0.3048 -0.1016)
			)
			(stroke
				(width 0)
				(type default)
			)
			(fill no)
			(layer "F.CrtYd")
		)
		(fp_line
			(start -0.3048 0.9906)
			(end 0.3048 0.9906)
			(stroke
				(width 0.1)
				(type default)
			)
			(layer "F.Fab")
		)
		(fp_line
			(start 0.3048 0.9906)
			(end 0.3048 -0.1016)
			(stroke
				(width 0.1)
				(type default)
			)
			(layer "F.Fab")
		)
		(fp_line
			(start -0.3048 -0.1016)
			(end -0.3048 0.9906)
			(stroke
				(width 0.1)
				(type default)
			)
			(layer "F.Fab")
		)
		(fp_line
			(start 0.3048 -0.1016)
			(end -0.3048 -0.1016)
			(stroke
				(width 0.1)
				(type default)
			)
			(layer "F.Fab")
		)
		(pad "1" smd rect
			(at 0 0 270)
			(size 0.508 0.508)
			(layers "F.Cu" "F.Mask" "F.Paste")
			(net "P3V3")
		)
		(pad "2" smd rect
			(at 0 0.889 270)
			(size 0.508 0.508)
			(layers "F.Cu" "F.Mask" "F.Paste")
			(net "GND")
		)
		(zone
			(layer "F.Cu")
			(hatch none 0.5)
			(connect_pads
				(clearance 0)
			)
			(min_thickness 0.25)
			(keepout
				(tracks not_allowed)
				(vias allowed)
				(pads allowed)
				(copperpour not_allowed)
				(footprints allowed)
			)
			(placement
				(enabled no)
				(sheetname "")
			)
			(fill
				(thermal_gap 0.5)
				(thermal_bridge_width 0.5)
				(island_removal_mode 0)
			)
			(polygon
				(pts
					(xy 473.192094 -141.862048) (xy 473.192094 -141.354048) (xy 473.573094 -141.354048) (xy 473.573094 -141.862048)
				)
			)
		)
		(zone
			(layer "F.Cu")
			(hatch none 0.5)
			(connect_pads
				(clearance 0)
			)
			(min_thickness 0.25)
			(keepout
				(tracks allowed)
				(vias not_allowed)
				(pads allowed)
				(copperpour not_allowed)
				(footprints allowed)
			)
			(placement
				(enabled no)
				(sheetname "")
			)
			(fill
				(thermal_gap 0.5)
				(thermal_bridge_width 0.5)
				(island_removal_mode 0)
			)
			(polygon
				(pts
					(xy 473.573094 -141.862048) (xy 473.573094 -141.354048) (xy 473.192094 -141.354048) (xy 473.192094 -141.862048)
				)
			)
		)
	)
	(footprint ""
		(layer "F.Cu")
		(at 426.4279 -124.0536 -90)
		(property "Reference" "R8B17"
			(at 0 0 270)
			(layer "F.SilkS")
			(hide yes)
			(effects
				(font
					(size 1.27 1.27)
				)
			)
		)
		(property "Value" ""
			(at 0 0 270)
			(layer "F.Fab")
			(effects
				(font
					(size 1.27 1.27)
				)
			)
		)
		(duplicate_pad_numbers_are_jumpers no)
		(fp_poly
			(pts
				(xy -0.2794 -0.1016) (xy 0.2794 -0.1016) (xy 0.2794 0.9906) (xy -0.2794 0.9906)
			)
			(stroke
				(width 0)
				(type default)
			)
			(fill no)
			(layer "F.CrtYd")
		)
		(fp_line
			(start -0.2794 0.9906)
			(end 0.2794 0.9906)
			(stroke
				(width 0.1)
				(type default)
			)
			(layer "F.Fab")
		)
		(fp_line
			(start 0.2794 0.9906)
			(end 0.2794 -0.1016)
			(stroke
				(width 0.1)
				(type default)
			)
			(layer "F.Fab")
		)
		(fp_line
			(start -0.2794 -0.1016)
			(end -0.2794 0.9906)
			(stroke
				(width 0.1)
				(type default)
			)
			(layer "F.Fab")
		)
		(fp_line
			(start 0.2794 -0.1016)
			(end -0.2794 -0.1016)
			(stroke
				(width 0.1)
				(type default)
			)
			(layer "F.Fab")
		)
		(pad "1" smd rect
			(at 0 0 270)
			(size 0.508 0.508)
			(layers "F.Cu" "F.Mask" "F.Paste")
			(net "PVPP_ABC")
		)
		(pad "2" smd rect
			(at 0 0.889 270)
			(size 0.508 0.508)
			(layers "F.Cu" "F.Mask" "F.Paste")
			(net "IRQ_HFI1_CPU0_LVT2_N")
		)
		(zone
			(layer "F.Cu")
			(hatch none 0.5)
			(connect_pads
				(clearance 0)
			)
			(min_thickness 0.25)
			(keepout
				(tracks not_allowed)
				(vias allowed)
				(pads allowed)
				(copperpour not_allowed)
				(footprints allowed)
			)
			(placement
				(enabled no)
				(sheetname "")
			)
			(fill
				(thermal_gap 0.5)
				(thermal_bridge_width 0.5)
				(island_removal_mode 0)
			)
			(polygon
				(pts
					(xy 425.7929 -124.3076) (xy 425.7929 -123.7996) (xy 426.1739 -123.7996) (xy 426.1739 -124.3076)
				)
			)
		)
		(zone
			(layer "F.Cu")
			(hatch none 0.5)
			(connect_pads
				(clearance 0)
			)
			(min_thickness 0.25)
			(keepout
				(tracks allowed)
				(vias not_allowed)
				(pads allowed)
				(copperpour not_allowed)
				(footprints allowed)
			)
			(placement
				(enabled no)
				(sheetname "")
			)
			(fill
				(thermal_gap 0.5)
				(thermal_bridge_width 0.5)
				(island_removal_mode 0)
			)
			(polygon
				(pts
					(xy 426.1739 -124.3076) (xy 426.1739 -123.7996) (xy 425.7929 -123.7996) (xy 425.7929 -124.3076)
				)
			)
		)
	)
)
